# TIMECARD (Time Appliance Project (Time Card)) — schematic netlist excerpt (pin names and nets, part order shuffled) for the footprints in the layout excerpt that follows; sources: Cadence DE-HDL packaged netlist, KiCad conversion of R4006-B0001-02_R01.brd

C307  CAPACITOR  0.01UF 25V 10%  pkg SMC_0201R  page 33 : \1\ = UNNAMED_525_CAPACITOR_I18_1 ; \2\ = SG
R305  RESISTOR  1KOHM 1%  pkg SMC_0402R_H016  page 20 : \1\ = UNNAMED_9_BNO080LGA28_I29_PS0 ; \2\ = SG

(kicad_pcb
	(version 20260206)
	(generator "pcbnew")
	(generator_version "10.0")
	(general
		(thickness 1.6)
		(legacy_teardrops no)
	)
	(paper "A4")
	(title_block
		(title "timecard-production-celestica-r4006 — R4006-B0001-02_R01.brd")
		(comment 1 "Time Appliance Project (Time Card) / footprints 63-64 of 1113")
	)
	(layers
		(0 "F.Cu" signal "TOP")
		(4 "In1.Cu" signal "L02_GND1")
		(6 "In2.Cu" signal "L03_SIG1")
		(8 "In3.Cu" signal "L04_GND2")
		(10 "In4.Cu" signal "L05_VCC1")
		(12 "In5.Cu" signal "L06_VCC2")
		(14 "In6.Cu" signal "L07_GND3")
		(16 "In7.Cu" signal "L08_SIG2")
		(18 "In8.Cu" signal "L09_GND4")
		(2 "B.Cu" signal "BOTTOM")
		(9 "F.Adhes" user "F.Adhesive")
		(11 "B.Adhes" user "B.Adhesive")
		(13 "F.Paste" user "Package Geometry/Pastemask Top")
		(15 "B.Paste" user "Package Geometry/Pastemask Bottom")
		(5 "F.SilkS" user "Ref Des/Silkscreen Top")
		(7 "B.SilkS" user "Ref Des/Silkscreen Bottom")
		(1 "F.Mask" user "Board Geometry/Soldermask Top")
		(3 "B.Mask" user "Board Geometry/Soldermask Bottom")
		(17 "Dwgs.User" user "User.Drawings")
		(19 "Cmts.User" user "User.Comments")
		(21 "Eco1.User" user "User.Eco1")
		(23 "Eco2.User" user "User.Eco2")
		(25 "Edge.Cuts" user "Board Geometry/Outline")
		(27 "Margin" user)
		(31 "F.CrtYd" user "Package Geometry/Place Bound Top")
		(29 "B.CrtYd" user "Package Geometry/Place Bound Bottom")
		(35 "F.Fab" user "Ref Des/Assembly Top")
		(33 "B.Fab" user "Ref Des/Assembly Bottom")
	)
	(footprint ""
		(layer "F.Cu")
		(at 80.772 -65.2526 180)
		(property "Reference" "R305"
			(at 10.287 19.16303 0)
			(unlocked yes)
			(layer "F.SilkS")
			(effects
				(font
					(size 0.7874 0.5842)
					(thickness 0.1524)
				)
			)
		)
		(property "Value" "VAL*"
			(at 0.02032 2.13233 180)
			(unlocked yes)
			(layer "F.Fab")
			(hide yes)
			(effects
				(font
					(size 0.7874 0.5842)
					(thickness 0.1524)
				)
			)
		)
		(property "Device Type" "RESISTOR-G155-11001-01,1KOHM,1%"
			(at 0.008382 1.210564 180)
			(unlocked yes)
			(layer "F.Fab")
			(hide yes)
			(effects
				(font
					(size 0.7874 0.5842)
					(thickness 0.1524)
				)
			)
		)
		(property "User Part Number" "PARTNUM*"
			(at 0.02032 4.024884 180)
			(unlocked yes)
			(layer "Cmts.User")
			(hide yes)
			(effects
				(font
					(size 0.7874 0.5842)
					(thickness 0.1524)
				)
			)
		)
		(property "Tolerance" "TOL*"
			(at 0.044704 3.05435 180)
			(unlocked yes)
			(layer "Cmts.User")
			(hide yes)
			(effects
				(font
					(size 0.7874 0.5842)
					(thickness 0.1524)
				)
			)
		)
		(duplicate_pad_numbers_are_jumpers no)
		(fp_line
			(start 1.143 0.5588)
			(end 1.143 -0.5588)
			(stroke
				(width 0.1)
				(type default)
			)
			(layer "F.SilkS")
		)
		(fp_line
			(start 1.143 -0.5588)
			(end -1.143 -0.5588)
			(stroke
				(width 0.1)
				(type default)
			)
			(layer "F.SilkS")
		)
		(fp_line
			(start -1.143 0.5588)
			(end 1.143 0.5588)
			(stroke
				(width 0.1)
				(type default)
			)
			(layer "F.SilkS")
		)
		(fp_line
			(start -1.143 -0.5588)
			(end -1.143 0.5588)
			(stroke
				(width 0.1)
				(type default)
			)
			(layer "F.SilkS")
		)
		(fp_rect
			(start 1.143 -0.5588)
			(end -1.143 0.5588)
			(stroke
				(width 0)
				(type default)
			)
			(fill no)
			(layer "F.CrtYd")
		)
		(fp_line
			(start 0.508 0.3048)
			(end 0.508 -0.3048)
			(stroke
				(width 0.1)
				(type default)
			)
			(layer "F.Fab")
		)
		(fp_line
			(start 0.508 -0.3048)
			(end -0.508 -0.3048)
			(stroke
				(width 0.1)
				(type default)
			)
			(layer "F.Fab")
		)
		(fp_line
			(start -0.508 0.3048)
			(end 0.508 0.3048)
			(stroke
				(width 0.1)
				(type default)
			)
			(layer "F.Fab")
		)
		(fp_line
			(start -0.508 -0.3048)
			(end -0.508 0.3048)
			(stroke
				(width 0.1)
				(type default)
			)
			(layer "F.Fab")
		)
		(pad "1" smd rect
			(at -0.5334 0 180)
			(size 0.7112 0.6096)
			(layers "F.Cu" "F.Mask" "F.Paste")
			(net "UNNAMED_9_BNO080LGA28_I29_PS0")
		)
		(pad "2" smd rect
			(at 0.5334 0 180)
			(size 0.7112 0.6096)
			(layers "F.Cu" "F.Mask" "F.Paste")
			(net "SG")
		)
		(zone
			(layer "F.Cu")
			(hatch none 0.5)
			(connect_pads
				(clearance 0)
			)
			(min_thickness 0.25)
			(keepout
				(tracks allowed)
				(vias not_allowed)
				(pads allowed)
				(copperpour not_allowed)
				(footprints allowed)
			)
			(placement
				(enabled no)
				(sheetname "")
			)
			(fill
				(thermal_gap 0.5)
				(thermal_bridge_width 0.5)
				(island_removal_mode 0)
			)
			(polygon
				(pts
					(xy 80.6958 -64.9478) (xy 80.8482 -64.9478) (xy 80.8482 -65.5574) (xy 80.6958 -65.5574)
				)
			)
		)
	)
	(footprint ""
		(layer "F.Cu")
		(at 43.815 -73.66 180)
		(property "Reference" "C307"
			(at -0.635 -1.18237 0)
			(unlocked yes)
			(layer "F.SilkS")
			(effects
				(font
					(size 0.7874 0.5842)
					(thickness 0.1524)
				)
			)
		)
		(property "Value" "VAL*"
			(at 0.193548 2.13614 180)
			(unlocked yes)
			(layer "F.Fab")
			(hide yes)
			(effects
				(font
					(size 0.7874 0.5842)
					(thickness 0.1524)
				)
			)
		)
		(property "User Part Number" "PARTNUM*"
			(at 0.216154 4.185666 180)
			(unlocked yes)
			(layer "Cmts.User")
			(hide yes)
			(effects
				(font
					(size 0.7874 0.5842)
					(thickness 0.1524)
				)
			)
		)
		(property "Device Type" "CAPACITOR-G104-0B103-EK,0.01UFA"
			(at 0.184404 1.180592 180)
			(unlocked yes)
			(layer "F.Fab")
			(hide yes)
			(effects
				(font
					(size 0.7874 0.5842)
					(thickness 0.1524)
				)
			)
		)
		(property "Tolerance" "TOL*"
			(at 0.216154 3.1496 180)
			(unlocked yes)
			(layer "Cmts.User")
			(hide yes)
			(effects
				(font
					(size 0.7874 0.5842)
					(thickness 0.1524)
				)
			)
		)
		(duplicate_pad_numbers_are_jumpers no)
		(fp_line
			(start 0.671322 0.4445)
			(end -0.671322 0.4445)
			(stroke
				(width 0.1)
				(type default)
			)
			(layer "F.SilkS")
		)
		(fp_line
			(start 0.671322 -0.4445)
			(end 0.671322 0.4445)
			(stroke
				(width 0.1)
				(type default)
			)
			(layer "F.SilkS")
		)
		(fp_line
			(start -0.671322 0.4445)
			(end -0.671322 -0.4445)
			(stroke
				(width 0.1)
				(type default)
			)
			(layer "F.SilkS")
		)
		(fp_line
			(start -0.671322 -0.4445)
			(end 0.671322 -0.4445)
			(stroke
				(width 0.1)
				(type default)
			)
			(layer "F.SilkS")
		)
		(fp_rect
			(start -0.671322 0.4445)
			(end 0.671322 -0.4445)
			(stroke
				(width 0)
				(type default)
			)
			(fill no)
			(layer "F.CrtYd")
		)
		(fp_line
			(start 0.31496 0.1651)
			(end 0.31496 -0.1651)
			(stroke
				(width 0.1)
				(type default)
			)
			(layer "F.Fab")
		)
		(fp_line
			(start 0.31496 -0.1651)
			(end -0.31496 -0.1651)
			(stroke
				(width 0.1)
				(type default)
			)
			(layer "F.Fab")
		)
		(fp_line
			(start -0.31496 0.1651)
			(end 0.31496 0.1651)
			(stroke
				(width 0.1)
				(type default)
			)
			(layer "F.Fab")
		)
		(fp_line
			(start -0.31496 -0.1651)
			(end -0.31496 0.1651)
			(stroke
				(width 0.1)
				(type default)
			)
			(layer "F.Fab")
		)
		(pad "1" smd rect
			(at -0.264922 0 180)
			(size 0.3048 0.381)
			(layers "F.Cu" "F.Mask" "F.Paste")
			(net "UNNAMED_525_CAPACITOR_I18_1")
		)
		(pad "2" smd rect
			(at 0.264922 0 180)
			(size 0.3048 0.381)
			(layers "F.Cu" "F.Mask" "F.Paste")
			(net "SG")
		)
		(zone
			(layer "F.Cu")
			(hatch none 0.5)
			(connect_pads
				(clearance 0)
			)
			(min_thickness 0.25)
			(keepout
				(tracks not_allowed)
				(vias allowed)
				(pads allowed)
				(copperpour not_allowed)
				(footprints allowed)
			)
			(placement
				(enabled no)
				(sheetname "")
			)
			(fill
				(thermal_gap 0.5)
				(thermal_bridge_width 0.5)
				(island_removal_mode 0)
			)
			(polygon
				(pts
					(xy 43.927522 -73.8505) (xy 43.702478 -73.8505) (xy 43.702478 -73.4695) (xy 43.927522 -73.4695)
				)
			)
		)
		(zone
			(layer "F.Cu")
			(hatch none 0.5)
			(connect_pads
				(clearance 0)
			)
			(min_thickness 0.25)
			(keepout
				(tracks allowed)
				(vias not_allowed)
				(pads allowed)
				(copperpour not_allowed)
				(footprints allowed)
			)
			(placement
				(enabled no)
				(sheetname "")
			)
			(fill
				(thermal_gap 0.5)
				(thermal_bridge_width 0.5)
				(island_removal_mode 0)
			)
			(polygon
				(pts
					(xy 43.927522 -73.4695) (xy 43.927522 -73.8505) (xy 43.702478 -73.8505) (xy 43.702478 -73.4695)
				)
			)
		)
	)
)
